FILE_TYPE = MULTI_PHYS_TABLE;

PART 'SCONN8_G802M0083150RD3HR'

{========================================================================================}
:VALUE                      | PART_TYPE | MATERIAL | PART_NUMBER    = STANDARD        | LIFECYCLE          | PART_NUMBER   | JEDEC_TYPE     | DESCRIPTION                            | MANUFTR | MANUF_PN            | RD_CMPLS_LVL | CMPLS_LVL | CLASS | DIP_SMD | FROM_PJ     | DATA                        | FP_ECN                  | EE_CHECK_LIST | CREATOR | CREATEDAY  | PSL | STATUS | ESD_CDM | ESD_HBM | ESD_MM | MSD | PIN_LENGTH_LONG_PIN | PIN_LENGTH_SHORT_PIN ;
{========================================================================================}
 'SCONN8_G802M0083150RD3HR' | 'SMLF'    | 'IO'     | 'DFHD08MS385'(!) = ''               | ''               | 'DFHD08MS385' |'HEADER2X4SXN'| 'CONN SMD HEADER 8P 2R MS(P1.27,H5.5)' | 'APL'   | 'G802M0083150RD3HR' | 'EP(V1)'     | ''        | 'IO'  | ''      | 'F0TG-CART' | 'APL_G802M0083150RD3HR.pdf' | 'G802M0083150RD3HR.msg' | ''            | ''      | '20220616' | ''  | ''     | ''      | ''      | ''     | ''  | '0 MILS'            | '0 MILS'            
 'SCONN8_G802M0083150RD3HR' | 'SMLF'    | 'EMPTY'  | 'DFHD08MS385'(!) = ''               | ''               | 'DFHD08MS385' |'HEADER2X4SXN'| 'CONN SMD HEADER 8P 2R MS(P1.27,H5.5)' | 'APL'   | 'G802M0083150RD3HR' | 'EP(V1)'     | ''        | 'IO'  | ''      | 'F0TG-CART' | 'APL_G802M0083150RD3HR.pdf' | 'G802M0083150RD3HR.msg' | ''            | ''      | '20220616' | ''  | ''     | ''      | ''      | ''     | ''  | '0 MILS'            | '0 MILS'            

END_PART

END.

